# TIMECARD (Time Appliance Project (Time Card)) — schematic parts with pin connectivity, parts 1098–1098 of 1119; source: Cadence DE-HDL packaged netlist (pstxprt.dat, pstxnet.dat, pstchip.dat)

U24  XC7A200T_2FBG484C_FBG484  XC7A100T-1FGG484I  pkg BGA484_906_P0394_V3  page 10  (pins 1-348 of 484)
  A1  IO_L1N_T0_AD4N_35  BI  = NC
  A2  GND_3  GROUND  = SG
  A3  GND_5  GROUND  = SG
  A4  MGTPTXN0_216  OUT  = CPU_RX_PCIE_MGT0_TXN
  A5  GND_6  GROUND  = SG
  A6  MGTPTXN2_216  OUT  = CPU_RX_PCIE_MGT2_TXN
  A7  GND_7  GROUND  = SG
  A8  MGTPRXN0_216  IN  = CPU_TX_PCIE_MGT_0_RXN
  A9  GND_8  GROUND  = SG
  A10  MGTPRXN2_216  IN  = CPU_TX_PCIE_MGT_2_RXN
  A11  GND_1  GROUND  = SG
  A12  GND_2  GROUND  = SG
  A13  IO_L10P_T1_16  BI  = FPGA_USR_LED1
  A14  IO_L10N_T1_16  BI  = FPGA_USR_LED0
  A15  IO_L9P_T1_DQS_16  BI  = NC
  A16  IO_L9N_T1_DQS_16  BI  = NC
  A17  VCCO_16_1  POWER  = XP3R3V_FPGA
  A18  IO_L17P_T2_16  BI  = FPGA_OUT_GPS_LED_RED_N
  A19  IO_L17N_T2_16  BI  = NC
  A20  IO_L16N_T2_16  BI  = FPGA_OUT_GPS_LED_GREEN_N
  A21  IO_L21N_T3_DQS_16  BI  = IO_L21N_16
  A22  GND_4  GROUND  = SG
  AA1  IO_L7P_T1_34  BI  = NC
  AA2  GND_10  GROUND  = SG
  AA3  IO_L9N_T1_DQS_34  BI  = NC
  AA4  IO_L11N_T1_SRCC_34  BI  = NC
  AA5  IO_L10P_T1_34  BI  = FPGA_OUT_MAC_PPS_IN1P
  AA6  IO_L18N_T2_34  BI  = NC
  AA7  VCCO_34_1  POWER  = XP2R5V_FPGA
  AA8  IO_L22P_T3_34  BI  = IO_L22P_34
  AA9  IO_L8P_T1_13  BI  = FPGA_IN_MAC_BITEOUT
  AA10  IO_L9P_T1_DQS_13  BI  = NC
  AA11  IO_L9N_T1_DQS_13  BI  = NC
  AA12  GND_9  GROUND  = SG
  AA13  IO_L3P_T0_DQS_13  BI  = FPGA_OUT_SN_EEPROM_WP
  AA14  IO_L5N_T0_13  BI  = NC
  AA15  IO_L4P_T0_13  BI  = FPGA_IO_FT_USBDET_RST_N
  AA16  IO_L1N_T0_13  BI  = NC
  AA17  VCCO_13_1  POWER  = XP3R3V_FPGA
  AA18  IO_L17P_T2_A14_D30_14  BI  = UART_MAC_RX_FPGA_TX
  AA19  \io_l15p_t2_dqs_rdwr_14*\  BI  = NC
  AA20  IO_L8P_T1_D11_14  BI  = ANT2_IN
  AA21  IO_L8N_T1_D12_14  BI  = ANT1_IN
  AA22  GND_11  GROUND  = SG
  AB1  IO_L7N_T1_34  BI  = NC
  AB2  IO_L8N_T1_34  BI  = FPGA_OUT_MAC_PPS_IN0N
  AB3  IO_L8P_T1_34  BI  = FPGA_OUT_MAC_PPS_IN0P
  AB4  VCCO_34_2  POWER  = XP2R5V_FPGA
  AB5  IO_L10N_T1_34  BI  = FPGA_OUT_MAC_PPS_IN1N
  AB6  IO_L20N_T3_34  BI  = IO_L20N_34
  AB7  IO_L20P_T3_34  BI  = IO_L20P_34
  AB8  IO_L22N_T3_34  BI  = IO_L22N_34
  AB9  GND_13  GROUND  = SG
  AB10  IO_L8N_T1_13  BI  = FPGA_IN_MAC_ALARM_OUT_N
  AB11  IO_L7P_T1_13  BI  = NC
  AB12  IO_L7N_T1_13  BI  = NC
  AB13  IO_L3N_T0_DQS_13  BI  = FPGA_OUT_SEC_EEPROM_WP
  AB14  VCCO_13_2  POWER  = XP3R3V_FPGA
  AB15  IO_L4N_T0_13  BI  = NC
  AB16  IO_L2P_T0_13  BI  = FPGA_EEPROM_I2C_SCL
  AB17  IO_L2N_T0_13  BI  = FPGA_EEPROM_I2C_SDA
  AB18  IO_L17N_T2_A13_D29_14  BI  = UART_MAC_TX_FPGA_RX
  AB19  GND_12  GROUND  = SG
  AB20  \io_l15n_t2_dqs_dout_cso_14*\  BI  = NC
  AB21  IO_L10P_T1_D14_14  BI  = NC
  AB22  IO_L10N_T1_D15_14  BI  = NC
  B1  IO_L1P_T0_AD4P_35  BI  = NC
  B2  IO_L2N_T0_AD12N_35  BI  = NC
  B3  GND_16  GROUND  = SG
  B4  MGTPTXP0_216  OUT  = CPU_RX_PCIE_MGT0_TXP
  B5  MGTAVTT_2  POWER  = FPGA_MGTAVTT
  B6  MGTPTXP2_216  OUT  = CPU_RX_PCIE_MGT2_TXP
  B7  MGTAVTT_3  POWER  = FPGA_MGTAVTT
  B8  MGTPRXP0_216  IN  = CPU_TX_PCIE_MGT_0_RXP
  B9  MGTAVTT_4  POWER  = FPGA_MGTAVTT
  B10  MGTPRXP2_216  IN  = CPU_TX_PCIE_MGT_2_RXP
  B11  MGTAVTT_1  POWER  = FPGA_MGTAVTT
  B12  GND_14  GROUND  = SG
  B13  IO_L8N_T1_16  BI  = LED_DATOUT0
  B14  VCCO_16_2  POWER  = XP3R3V_FPGA
  B15  IO_L7P_T1_16  BI  = NC
  B16  IO_L7N_T1_16  BI  = NC
  B17  IO_L11P_T1_SRCC_16  BI  = NC
  B18  IO_L11N_T1_SRCC_16  BI  = NC
  B19  GND_15  GROUND  = SG
  B20  IO_L16P_T2_16  BI  = FPGA_OUT_GPS_LED_BLUE_N
  B21  IO_L21P_T3_DQS_16  BI  = IO_L21P_16
  B22  IO_L20N_T3_16  BI  = IO_L20N_16
  C1  VCCO_35_1  POWER  = XP2R5V_FPGA
  C2  IO_L2P_T0_AD12P_35  BI  = NC
  C3  GND_20  GROUND  = SG
  C4  MGTAVTT_5  POWER  = FPGA_MGTAVTT
  C5  MGTPTXN1_216  OUT  = CPU_RX_PCIE_MGT1_TXN
  C6  GND_21  GROUND  = SG
  C7  MGTPTXN3_216  OUT  = CPU_RX_PCIE_MGT3_TXN
  C8  MGTAVTT_6  POWER  = FPGA_MGTAVTT
  C9  MGTPRXN3_216  IN  = CPU_TX_PCIE_MGT_3_RXN
  C10  GND_17  GROUND  = SG
  C11  MGTPRXN1_216  IN  = CPU_TX_PCIE_MGT_1_RXN
  C12  GND_18  GROUND  = SG
  C13  IO_L8P_T1_16  BI  = LED_DATOUT1
  C14  IO_L3P_T0_DQS_16  BI  = FPGA_OUT_SMA2_LED_BLUE_N
  C15  IO_L3N_T0_DQS_16  BI  = FPGA_OUT_SMA2_LED_GREEN_N
  C16  GND_19  GROUND  = SG
  C17  IO_L12N_T1_MRCC_16  BI  = FPGA_OUT_SMA3_LED_GREEN_N
  C18  IO_L13P_T2_MRCC_16  BI  = FPGA_OUT_SMA3_LED_RED_N
  C19  IO_L13N_T2_MRCC_16  BI  = NC
  C20  IO_L19N_T3_VREF_16  BI  = NC
  C21  VCCO_16_3  POWER  = XP3R3V_FPGA
  C22  IO_L20P_T3_16  BI  = IO_L20P_16
  D1  IO_L3N_T0_DQS_AD5N_35  BI  = NC
  D2  IO_L4N_T0_35  BI  = NC
  D3  GND_24  GROUND  = SG
  D4  GND_25  GROUND  = SG
  D5  MGTPTXP1_216  OUT  = CPU_RX_PCIE_MGT1_TXP
  D6  MGTAVCC_2  POWER  = XP1R0V_FPGA_MGTAVCC
  D7  MGTPTXP3_216  OUT  = CPU_RX_PCIE_MGT3_TXP
  D8  GND_26  GROUND  = SG
  D9  MGTPRXP3_216  IN  = CPU_TX_PCIE_MGT_3_RXP
  D10  MGTAVCC_1  POWER  = XP1R0V_FPGA_MGTAVCC
  D11  MGTPRXP1_216  IN  = CPU_TX_PCIE_MGT_1_RXP
  D12  GND_22  GROUND  = SG
  D13  GND_23  GROUND  = SG
  D14  IO_L6P_T0_16  BI  = LED_DATOUT2
  D15  IO_L6N_T0_VREF_16  BI  = LED_DATOUT3
  D16  IO_L5N_T0_16  BI  = NC
  D17  IO_L12P_T1_MRCC_16  BI  = FPGA_OUT_SMA3_LED_BLUE_N
  D18  VCCO_16_4  POWER  = XP3R3V_FPGA
  D19  IO_L14N_T2_SRCC_16  BI  = FPGA_OUT_SMA4_LED_GREEN_N
  D20  IO_L19P_T3_16  BI  = NC
  D21  IO_L23N_T3_16  BI  = IO_L23N_16
  D22  IO_L22N_T3_16  BI  = IO_L22N_16
  E1  IO_L3P_T0_DQS_AD5P_35  BI  = NC
  E2  IO_L4P_T0_35  BI  = NC
  E3  IO_L6N_T0_VREF_35  BI  = NC
  E4  GND_29  GROUND  = SG
  E5  GND_30  GROUND  = SG
  E6  MGTREFCLK0N_216  IN  = MHZ125CLKN_CLKIN
  E7  GND_31  GROUND  = SG
  E8  MGTAVCC_3  POWER  = XP1R0V_FPGA_MGTAVCC
  E9  GND_32  GROUND  = SG
  E10  MGTREFCLK1N_216  IN  = PCIE_REFCLKN
  E11  GND_27  GROUND  = SG
  E12  VCCBATT_0  POWER  = XP1R8V_FPGA_VCCAUX
  E13  IO_L4P_T0_16  BI  = FPGA_OUT_SMA2_LED_RED_N
  E14  IO_L4N_T0_16  BI  = NC
  E15  VCCO_16_5  POWER  = XP3R3V_FPGA
  E16  IO_L5P_T0_16  BI  = NC
  E17  IO_L2N_T0_16  BI  = NC
  E18  IO_L15N_T2_DQS_16  BI  = NC
  E19  IO_L14P_T2_SRCC_16  BI  = FPGA_OUT_SMA4_LED_BLUE_N
  E20  GND_28  GROUND  = SG
  E21  IO_L23P_T3_16  BI  = IO_L23P_16
  E22  IO_L22P_T3_16  BI  = IO_L22P_16
  F1  IO_L5N_T0_AD13N_35  BI  = NC
  F2  VCCO_35_2  POWER  = XP2R5V_FPGA
  F3  IO_L6P_T0_35  BI  = NC
  F4  IO_0_35  BI  = NC
  F5  GND_35  GROUND  = SG
  F6  MGTREFCLK0P_216  IN  = MHZ125CLKP_CLKIN
  F7  MGTAVCC_4  POWER  = XP1R0V_FPGA_MGTAVCC
  F8  MGTRREF_216  IN  = FPGA_MGTRREF
  F9  MGTAVCC_5  POWER  = XP1R0V_FPGA_MGTAVCC
  F10  MGTREFCLK1P_216  IN  = PCIE_REFCLKP
  F11  GND_33  GROUND  = SG
  F12  VCCO_0_1  POWER  = XP3R3V_FPGA
  F13  IO_L1P_T0_16  BI  = FPGA_OUT_SMA1_LED_BLUE_N
  F14  IO_L1N_T0_16  BI  = FPGA_OUT_SMA1_LED_GREEN_N
  F15  IO_0_16  BI  = NC
  F16  IO_L2P_T0_16  BI  = FPGA_OUT_SMA1_LED_RED_N
  F17  GND_34  GROUND  = SG
  F18  IO_L15P_T2_DQS_16  BI  = FPGA_OUT_SMA4_LED_RED_N
  F19  IO_L18P_T2_16  BI  = NC
  F20  IO_L18N_T2_16  BI  = NC
  F21  IO_25_16  BI  = NC
  F22  VCCO_16_6  POWER  = XP3R3V_FPGA
  G1  IO_L5P_T0_AD13P_35  BI  = NC
  G2  IO_L8N_T1_AD14N_35  BI  = NC
  G3  IO_L11N_T1_SRCC_35  BI  = NC
  G4  IO_L12N_T1_MRCC_35  BI  = NC
  G5  GND_39  GROUND  = SG
  G6  GND_40  GROUND  = SG
  G7  GND_41  GROUND  = SG
  G8  GND_42  GROUND  = SG
  G9  GND_43  GROUND  = SG
  G10  GND_36  GROUND  = SG
  G11  DONE_0  BI  = FPGA_DONE
  G12  GND_37  GROUND  = SG
  G13  IO_L1N_T0_AD0N_15  BI  = FPGA_OUT_MUX2_SEL
  G14  GND_38  GROUND  = SG
  G15  IO_L2P_T0_AD8P_15  BI  = FPGA_OUT_MUX3_SEL
  G16  IO_L2N_T0_AD8N_15  BI  = NC
  G17  IO_L4P_T0_15  BI  = NC
  G18  IO_L4N_T0_15  BI  = NC
  G19  VCCO_15_1  POWER  = XP3R3V_FPGA
  G20  IO_L8N_T1_AD10N_15  BI  = FPGA_IO_3
  G21  IO_L24P_T3_16  BI  = IO_L24P_16
  G22  IO_L24N_T3_16  BI  = IO_L24N_16
  H1  GND_44  GROUND  = SG
  H2  IO_L8P_T1_AD14P_35  BI  = NC
  H3  IO_L11P_T1_SRCC_35  BI  = NC
  H4  IO_L12P_T1_MRCC_35  BI  = NC
  H5  IO_L10N_T1_AD15N_35  BI  = NC
  H6  VCCO_35_3  POWER  = XP2R5V_FPGA
  H7  GND_47  GROUND  = SG
  H8  VCCINT_2  POWER  = XP1R0V_FPGA_VCCINT
  H9  GND_48  GROUND  = SG
  H10  VCCINT_1  POWER  = XP1R0V_FPGA_VCCINT
  H11  GND_45  GROUND  = SG
  H12  VCCAUX_1  POWER  = XP1R8V_FPGA_VCCAUX
  H13  IO_L1P_T0_AD0P_15  BI  = FPGA_OUT_MUX1_SEL
  H14  IO_L3N_T0_DQS_AD1N_15  BI  = SMA4_SIG_OUT_BF_EN_N
  H15  IO_L5N_T0_AD9N_15  BI  = SMA3_SIG_IN_BF_EN_N
  H16  VCCO_15_2  POWER  = XP3R3V_FPGA
  H17  IO_L6P_T0_15  BI  = NC
  H18  IO_L6N_T0_VREF_15  BI  = NC
  H19  IO_L12N_T1_MRCC_15  BI  = FPGA_OUT_SHT3X_RST_N
  H20  IO_L8P_T1_AD10P_15  BI  = FPGA_IO_2
  H21  GND_46  GROUND  = SG
  H22  IO_L7N_T1_AD2N_15  BI  = FPGA_IO_1
  J1  IO_L7N_T1_AD6N_35  BI  = NC
  J2  IO_L9N_T1_DQS_AD7N_35  BI  = NC
  J3  VCCO_35_4  POWER  = XP2R5V_FPGA
  J4  IO_L13N_T2_MRCC_35  BI  = NC
  J5  IO_L10P_T1_AD15P_35  BI  = NC
  J6  IO_L17N_T2_35  BI  = NC
  J7  VCCINT_3  POWER  = XP1R0V_FPGA_VCCINT
  J8  GND_52  GROUND  = SG
  J9  VCCINT_4  POWER  = XP1R0V_FPGA_VCCINT
  J10  GND_49  GROUND  = SG
  J11  VCCBRAM_1  POWER  = XP1R0V_FPGA_VCCINT
  J12  GND_50  GROUND  = SG
  J13  VCCO_15_3  POWER  = XP3R3V_FPGA
  J14  IO_L3P_T0_DQS_AD1P_15  BI  = SMA4_SIG_IN_BF_EN_N
  J15  IO_L5P_T0_AD9P_15  BI  = SMA3_SIG_OUT_BF_EN_N
  J16  IO_0_15  BI  = NC
  J17  IO_L21N_T3_DQS_A18_15  BI  = FPGA_OUT_BNO080_RST_N
  J18  GND_51  GROUND  = SG
  J19  IO_L12P_T1_MRCC_15  BI  = FPGA_IN_SHT3X_ALERT_N
  J20  IO_L11P_T1_SRCC_15  BI  = FPGA_IN_RST_DLY_N
  J21  IO_L11N_T1_SRCC_15  BI  = NC
  J22  IO_L7P_T1_AD2P_15  BI  = FPGA_IO_0
  K1  IO_L7P_T1_AD6P_35  BI  = NC
  K2  IO_L9P_T1_DQS_AD7P_35  BI  = NC
  K3  IO_L14N_T2_SRCC_35  BI  = NC
  K4  IO_L13P_T2_MRCC_35  BI  = NC
  K5  GND_55  GROUND  = SG
  K6  IO_L17P_T2_35  BI  = NC
  K7  GND_56  GROUND  = SG
  K8  VCCINT_5  POWER  = XP1R0V_FPGA_VCCINT
  K9  GNDADC_0  GROUND  = SG
  K10  VCCADC_0  POWER  = XP1R8V_FPGA_VCCAUX
  K11  GND_53  GROUND  = SG
  K12  VCCAUX_2  POWER  = XP1R8V_FPGA_VCCAUX
  K13  IO_L19P_T3_A22_15  BI  = SMA1_SIG_OUT_BF_EN_N
  K14  IO_L19N_T3_A21_VREF_15  BI  = SMA1_SIG_IN_BF_EN_N
  K15  GND_54  GROUND  = SG
  K16  IO_L23N_T3_FWE_B_15  BI  = FPGA_OUT_I2C_BUFFER_EN
  K17  IO_L21P_T3_DQS_15  BI  = NC
  K18  IO_L13P_T2_MRCC_15  BI  = NC
  K19  IO_L13N_T2_MRCC_15  BI  = NC
  K20  VCCO_15_4  POWER  = XP3R3V_FPGA
  K21  IO_L9P_T1_DQS_AD3P_15  BI  = FPGA_IO_4
  K22  IO_L9N_T1_DQS_AD3N_15  BI  = FPGA_IO_5
  L1  IO_L15N_T2_DQS_35  BI  = NC
  L2  GND_57  GROUND  = SG
  L3  IO_L14P_T2_SRCC_35  BI  = NC
  L4  IO_L18N_T2_35  BI  = NC
  L5  IO_L18P_T2_35  BI  = NC
  L6  IO_25_35  BI  = NC
  L7  VCCINT_6  POWER  = XP1R0V_FPGA_VCCINT
  L8  GND_59  GROUND  = SG
  L9  VREFN_0  BI  = SG
  L10  VP_0  IN  = SG
  L11  VCCBRAM_2  POWER  = XP1R0V_FPGA_VCCINT
  L12  CCLK_0  BI  = CCLK_0
  L13  IO_L20N_T3_A19_15  BI  = SMA2_SIG_IN_BF_EN_N
  L14  IO_L22P_T3_A17_15  BI  = FPGA_IN_BNO080_INT_N
  L15  IO_L22N_T3_A16_15  BI  = FPGA_OUT_BNO080_BOOT_N
  L16  IO_L23P_T3_FOE_B_15  BI  = NC
  L17  VCCO_15_5  POWER  = XP3R3V_FPGA
  L18  IO_L16N_T2_A27_15  BI  = NC
  L19  IO_L14P_T2_SRCC_15  BI  = NC
  L20  IO_L14N_T2_SRCC_15  BI  = NC
  L21  IO_L10N_T1_AD11N_15  BI  = FPGA_IO_7
  L22  GND_58  GROUND  = SG
  M1  IO_L15P_T2_DQS_35  BI  = NC
  M2  IO_L16N_T2_35  BI  = NC
  M3  IO_L16P_T2_35  BI  = NC
  M4  VCCO_35_5  POWER  = XP2R5V_FPGA
  M5  IO_L23N_T3_35  BI  = IO_L23N_35
  M6  IO_L23P_T3_35  BI  = IO_L23P_35
  M7  GND_62  GROUND  = SG
  M8  VCCINT_7  POWER  = XP1R0V_FPGA_VCCINT
  M9  VN_0  IN  = SG
  M10  VREFP_0  BI  = SG
  M11  GND_60  GROUND  = SG
  M12  VCCAUX_3  POWER  = XP1R8V_FPGA_VCCAUX
  M13  IO_L20P_T3_A20_15  BI  = SMA2_SIG_OUT_BF_EN_N
  M14  VCCO_14_1  POWER  = XP3R3V_FPGA
  M15  IO_L24P_T3_RS1_15  BI  = FPGA_IN_MAC_USB_OC_N
  M16  IO_L24N_T3_RS0_15  BI  = RSVD_DBG_USB_MUX_SEL
  M17  IO_25_15  BI  = NC
  M18  IO_L16P_T2_A28_15  BI  = FPGA_IN_LM75B_INT3_N
  M19  GND_61  GROUND  = SG
  M20  IO_L18N_T2_A23_15  BI  = NC
  M21  IO_L10P_T1_AD11P_15  BI  = FPGA_IO_6
  M22  IO_L15N_T2_DQS_ADV_B_15  BI  = FPGA_IN_LM75B_INT2_N
  N1  VCCO_35_6  POWER  = XP2R5V_FPGA
  N2  IO_L22N_T3_35  BI  = IO_L22N_35
  N3  IO_L19N_T3_VREF_35  BI  = NC
  N4  IO_L19P_T3_35  BI  = NC
  N5  IO_L24N_T3_35  BI  = IO_L24N_35
  N6  GND_64  GROUND  = SG
  N7  VCCINT_8  POWER  = XP1R0V_FPGA_VCCINT
  N8  GND_65  GROUND  = SG
  N9  DXN_0  IN  = SG
  N10  DXP_0  IN  = SG
  N11  VCCBRAM_3  POWER  = XP1R0V_FPGA_VCCINT
  N12  \program_0*\  BI  = FPGA_PROGRAM_N
  N13  IO_L23P_T3_A03_D19_14  BI  = NC
  N14  IO_L23N_T3_A02_D18_14  BI  = NC
  N15  IO_25_14  BI  = UART_GPS_TX_FPGA_RX
  N16  GND_63  GROUND  = SG
  N17  IO_L21P_T3_DQS_14  BI  = FPGA_PCA9546_I2C_SCL
  N18  IO_L17P_T2_A26_15  BI  = FPGA_BRD_REV2
  N19  IO_L17N_T2_A25_15  BI  = FPGA_BRD_REV1
  N20  IO_L18P_T2_A24_15  BI  = FPGA_BRD_REV0
  N21  VCCO_15_6  POWER  = XP3R3V_FPGA
  N22  IO_L15P_T2_DQS_15  BI  = FPGA_IN_LM75B_INT1_N
  P1  IO_L20N_T3_35  BI  = IO_L20N_35
  P2  IO_L22P_T3_35  BI  = IO_L22P_35
  P3  GND_68  GROUND  = SG
  P4  IO_L21N_T3_DQS_35  BI  = IO_L21N_35
  P5  IO_L21P_T3_DQS_35  BI  = IO_L21P_35
  P6  IO_L24P_T3_35  BI  = IO_L24P_35
  P7  GND_69  GROUND  = SG
  P8  VCCINT_10  POWER  = XP1R0V_FPGA_VCCINT
  P9  GND_70  GROUND  = SG
  P10  VCCINT_9  POWER  = XP1R0V_FPGA_VCCINT
  P11  GND_66  GROUND  = SG
  P12  VCCAUX_4  POWER  = XP1R8V_FPGA_VCCAUX
  P13  GND_67  GROUND  = SG
  P14  IO_L19P_T3_A10_D26_14  BI  = MAC_USB_DP
  P15  IO_L22P_T3_A05_D21_14  BI  = UART_FT4232_RX_FPGA_TX
  P16  IO_L24P_T3_A01_D17_14  BI  = UART_FT4232_TX_FPGA_RX
  P17  IO_L21N_T3_DQS_A06_D22_14  BI  = NC
  P18  VCCO_14_2  POWER  = XP3R3V_FPGA
